FILE_TYPE=LIBRARY_PARTS;
primitive 'SCONN288_ADR50017P130CC';
  pin
    'VIN_MGMT':
      PIN_NUMBER='(3,0,0)';
      PINUSE='POWER';
      NO_LOAD_CHECK='Both';
      NO_IO_CHECK='Both';
      NO_ASSERT_CHECK='TRUE';
      NO_DIR_CHECK='TRUE';
      ALLOW_CONNECT='TRUE';
    'RFU0':
      PIN_NUMBER='(2,0,0)';
      OUTPUT_TYPE='(TS,TS)';
      INPUT_LOAD='(-0.01,0.01)';
      OUTPUT_LOAD='(1.0,-1.0)';
    'RFU1':
      PIN_NUMBER='(144,0,0)';
      OUTPUT_TYPE='(TS,TS)';
      INPUT_LOAD='(-0.01,0.01)';
      OUTPUT_LOAD='(1.0,-1.0)';
    'RFU2':
      PIN_NUMBER='(149,0,0)';
      OUTPUT_TYPE='(TS,TS)';
      INPUT_LOAD='(-0.01,0.01)';
      OUTPUT_LOAD='(1.0,-1.0)';
    'RFU3':
      PIN_NUMBER='(150,0,0)';
      OUTPUT_TYPE='(TS,TS)';
      INPUT_LOAD='(-0.01,0.01)';
      OUTPUT_LOAD='(1.0,-1.0)';
    'RFU4':
      PIN_NUMBER='(220,0,0)';
      OUTPUT_TYPE='(TS,TS)';
      INPUT_LOAD='(-0.01,0.01)';
      OUTPUT_LOAD='(1.0,-1.0)';
    'RFU5':
      PIN_NUMBER='(231,0,0)';
      OUTPUT_TYPE='(TS,TS)';
      INPUT_LOAD='(-0.01,0.01)';
      OUTPUT_LOAD='(1.0,-1.0)';
    'RFU6':
      PIN_NUMBER='(232,0,0)';
      OUTPUT_TYPE='(TS,TS)';
      INPUT_LOAD='(-0.01,0.01)';
      OUTPUT_LOAD='(1.0,-1.0)';
    '-RESET':
      PIN_NUMBER='(207,0,0)';
      INPUT_LOAD='(-0.01,0.01)';
    '-PWR_GOOD||FAIL':
      PIN_NUMBER='(147,0,0)';
      BIDIRECTIONAL='TRUE';
      INPUT_LOAD='(-0.01,0.01)';
      OUTPUT_LOAD='(1.0,-1.0)';
    'PAR_B':
      PIN_NUMBER='(227,0,0)';
      INPUT_LOAD='(-0.01,0.01)';
    'PAR_A':
      PIN_NUMBER='(74,0,0)';
      INPUT_LOAD='(-0.01,0.01)';
    '-LBS||RSP_B':
      PIN_NUMBER='(87,0,0)';
      OUTPUT_LOAD='(1.0,-1.0)';
    '-LBD||RSP_A':
      PIN_NUMBER='(86,0,0)';
      OUTPUT_LOAD='(1.0,-1.0)';
    'HSDA':
      PIN_NUMBER='(5,0,0)';
      BIDIRECTIONAL='TRUE';
      INPUT_LOAD='(-0.01,0.01)';
      OUTPUT_LOAD='(1.0,-1.0)';
    'HSCL':
      PIN_NUMBER='(4,0,0)';
      INPUT_LOAD='(-0.01,0.01)';
    'HSA':
      PIN_NUMBER='(148,0,0)';
      INPUT_LOAD='(-0.01,0.01)';
    'DQ0_B':
      PIN_NUMBER='(100,0,0)';
      BIDIRECTIONAL='TRUE';
      INPUT_LOAD='(-0.01,0.01)';
      OUTPUT_LOAD='(1.0,-1.0)';
    'DQ1_B':
      PIN_NUMBER='(102,0,0)';
      BIDIRECTIONAL='TRUE';
      INPUT_LOAD='(-0.01,0.01)';
      OUTPUT_LOAD='(1.0,-1.0)';
    'DQ2_B':
      PIN_NUMBER='(245,0,0)';
      BIDIRECTIONAL='TRUE';
      INPUT_LOAD='(-0.01,0.01)';
      OUTPUT_LOAD='(1.0,-1.0)';
    'DQ3_B':
      PIN_NUMBER='(247,0,0)';
      BIDIRECTIONAL='TRUE';
      INPUT_LOAD='(-0.01,0.01)';
      OUTPUT_LOAD='(1.0,-1.0)';
    'DQ4_B':
      PIN_NUMBER='(107,0,0)';
      BIDIRECTIONAL='TRUE';
      INPUT_LOAD='(-0.01,0.01)';
      OUTPUT_LOAD='(1.0,-1.0)';
    'DQ5_B':
      PIN_NUMBER='(109,0,0)';
      BIDIRECTIONAL='TRUE';
      INPUT_LOAD='(-0.01,0.01)';
      OUTPUT_LOAD='(1.0,-1.0)';
    'DQ6_B':
      PIN_NUMBER='(252,0,0)';
      BIDIRECTIONAL='TRUE';
      INPUT_LOAD='(-0.01,0.01)';
      OUTPUT_LOAD='(1.0,-1.0)';
    'DQ7_B':
      PIN_NUMBER='(254,0,0)';
      BIDIRECTIONAL='TRUE';
      INPUT_LOAD='(-0.01,0.01)';
      OUTPUT_LOAD='(1.0,-1.0)';
    'DQ8_B':
      PIN_NUMBER='(111,0,0)';
      BIDIRECTIONAL='TRUE';
      INPUT_LOAD='(-0.01,0.01)';
      OUTPUT_LOAD='(1.0,-1.0)';
    'DQ9_B':
      PIN_NUMBER='(113,0,0)';
      BIDIRECTIONAL='TRUE';
      INPUT_LOAD='(-0.01,0.01)';
      OUTPUT_LOAD='(1.0,-1.0)';
    'DQ10_B':
      PIN_NUMBER='(256,0,0)';
      BIDIRECTIONAL='TRUE';
      INPUT_LOAD='(-0.01,0.01)';
      OUTPUT_LOAD='(1.0,-1.0)';
    'DQ11_B':
      PIN_NUMBER='(258,0,0)';
      BIDIRECTIONAL='TRUE';
      INPUT_LOAD='(-0.01,0.01)';
      OUTPUT_LOAD='(1.0,-1.0)';
    'DQ12_B':
      PIN_NUMBER='(118,0,0)';
      BIDIRECTIONAL='TRUE';
      INPUT_LOAD='(-0.01,0.01)';
      OUTPUT_LOAD='(1.0,-1.0)';
    'DQ13_B':
      PIN_NUMBER='(120,0,0)';
      BIDIRECTIONAL='TRUE';
      INPUT_LOAD='(-0.01,0.01)';
      OUTPUT_LOAD='(1.0,-1.0)';
    'DQ14_B':
      PIN_NUMBER='(263,0,0)';
      BIDIRECTIONAL='TRUE';
      INPUT_LOAD='(-0.01,0.01)';
      OUTPUT_LOAD='(1.0,-1.0)';
    'DQ15_B':
      PIN_NUMBER='(265,0,0)';
      BIDIRECTIONAL='TRUE';
      INPUT_LOAD='(-0.01,0.01)';
      OUTPUT_LOAD='(1.0,-1.0)';
    'DQ16_B':
      PIN_NUMBER='(122,0,0)';
      BIDIRECTIONAL='TRUE';
      INPUT_LOAD='(-0.01,0.01)';
      OUTPUT_LOAD='(1.0,-1.0)';
    'DQ17_B':
      PIN_NUMBER='(124,0,0)';
      BIDIRECTIONAL='TRUE';
      INPUT_LOAD='(-0.01,0.01)';
      OUTPUT_LOAD='(1.0,-1.0)';
    'DQ18_B':
      PIN_NUMBER='(267,0,0)';
      BIDIRECTIONAL='TRUE';
      INPUT_LOAD='(-0.01,0.01)';
      OUTPUT_LOAD='(1.0,-1.0)';
    'DQ19_B':
      PIN_NUMBER='(269,0,0)';
      BIDIRECTIONAL='TRUE';
      INPUT_LOAD='(-0.01,0.01)';
      OUTPUT_LOAD='(1.0,-1.0)';
    'DQ20_B':
      PIN_NUMBER='(129,0,0)';
      BIDIRECTIONAL='TRUE';
      INPUT_LOAD='(-0.01,0.01)';
      OUTPUT_LOAD='(1.0,-1.0)';
    'DQ21_B':
      PIN_NUMBER='(131,0,0)';
      BIDIRECTIONAL='TRUE';
      INPUT_LOAD='(-0.01,0.01)';
      OUTPUT_LOAD='(1.0,-1.0)';
    'DQ22_B':
      PIN_NUMBER='(274,0,0)';
      BIDIRECTIONAL='TRUE';
      INPUT_LOAD='(-0.01,0.01)';
      OUTPUT_LOAD='(1.0,-1.0)';
    'DQ23_B':
      PIN_NUMBER='(276,0,0)';
      BIDIRECTIONAL='TRUE';
      INPUT_LOAD='(-0.01,0.01)';
      OUTPUT_LOAD='(1.0,-1.0)';
    'DQ24_B':
      PIN_NUMBER='(133,0,0)';
      BIDIRECTIONAL='TRUE';
      INPUT_LOAD='(-0.01,0.01)';
      OUTPUT_LOAD='(1.0,-1.0)';
    'DQ25_B':
      PIN_NUMBER='(135,0,0)';
      BIDIRECTIONAL='TRUE';
      INPUT_LOAD='(-0.01,0.01)';
      OUTPUT_LOAD='(1.0,-1.0)';
    'DQ26_B':
      PIN_NUMBER='(278,0,0)';
      BIDIRECTIONAL='TRUE';
      INPUT_LOAD='(-0.01,0.01)';
      OUTPUT_LOAD='(1.0,-1.0)';
    'DQ27_B':
      PIN_NUMBER='(280,0,0)';
      BIDIRECTIONAL='TRUE';
      INPUT_LOAD='(-0.01,0.01)';
      OUTPUT_LOAD='(1.0,-1.0)';
    'DQ28_B':
      PIN_NUMBER='(140,0,0)';
      BIDIRECTIONAL='TRUE';
      INPUT_LOAD='(-0.01,0.01)';
      OUTPUT_LOAD='(1.0,-1.0)';
    'DQ29_B':
      PIN_NUMBER='(142,0,0)';
      BIDIRECTIONAL='TRUE';
      INPUT_LOAD='(-0.01,0.01)';
      OUTPUT_LOAD='(1.0,-1.0)';
    'DQ30_B':
      PIN_NUMBER='(285,0,0)';
      BIDIRECTIONAL='TRUE';
      INPUT_LOAD='(-0.01,0.01)';
      OUTPUT_LOAD='(1.0,-1.0)';
    'DQ31_B':
      PIN_NUMBER='(287,0,0)';
      BIDIRECTIONAL='TRUE';
      INPUT_LOAD='(-0.01,0.01)';
      OUTPUT_LOAD='(1.0,-1.0)';
    'DQ0_A':
      PIN_NUMBER='(7,0,0)';
      BIDIRECTIONAL='TRUE';
      INPUT_LOAD='(-0.01,0.01)';
      OUTPUT_LOAD='(1.0,-1.0)';
    'DQ1_A':
      PIN_NUMBER='(9,0,0)';
      BIDIRECTIONAL='TRUE';
      INPUT_LOAD='(-0.01,0.01)';
      OUTPUT_LOAD='(1.0,-1.0)';
    'DQ2_A':
      PIN_NUMBER='(152,0,0)';
      BIDIRECTIONAL='TRUE';
      INPUT_LOAD='(-0.01,0.01)';
      OUTPUT_LOAD='(1.0,-1.0)';
    'DQ3_A':
      PIN_NUMBER='(154,0,0)';
      BIDIRECTIONAL='TRUE';
      INPUT_LOAD='(-0.01,0.01)';
      OUTPUT_LOAD='(1.0,-1.0)';
    'DQ4_A':
      PIN_NUMBER='(14,0,0)';
      BIDIRECTIONAL='TRUE';
      INPUT_LOAD='(-0.01,0.01)';
      OUTPUT_LOAD='(1.0,-1.0)';
    'DQ5_A':
      PIN_NUMBER='(16,0,0)';
      BIDIRECTIONAL='TRUE';
      INPUT_LOAD='(-0.01,0.01)';
      OUTPUT_LOAD='(1.0,-1.0)';
    'DQ6_A':
      PIN_NUMBER='(159,0,0)';
      BIDIRECTIONAL='TRUE';
      INPUT_LOAD='(-0.01,0.01)';
      OUTPUT_LOAD='(1.0,-1.0)';
    'DQ7_A':
      PIN_NUMBER='(161,0,0)';
      BIDIRECTIONAL='TRUE';
      INPUT_LOAD='(-0.01,0.01)';
      OUTPUT_LOAD='(1.0,-1.0)';
    'DQ8_A':
      PIN_NUMBER='(18,0,0)';
      BIDIRECTIONAL='TRUE';
      INPUT_LOAD='(-0.01,0.01)';
      OUTPUT_LOAD='(1.0,-1.0)';
    'DQ9_A':
      PIN_NUMBER='(20,0,0)';
      BIDIRECTIONAL='TRUE';
      INPUT_LOAD='(-0.01,0.01)';
      OUTPUT_LOAD='(1.0,-1.0)';
    'DQ10_A':
      PIN_NUMBER='(163,0,0)';
      BIDIRECTIONAL='TRUE';
      INPUT_LOAD='(-0.01,0.01)';
      OUTPUT_LOAD='(1.0,-1.0)';
    'DQ11_A':
      PIN_NUMBER='(165,0,0)';
      BIDIRECTIONAL='TRUE';
      INPUT_LOAD='(-0.01,0.01)';
      OUTPUT_LOAD='(1.0,-1.0)';
    'DQ12_A':
      PIN_NUMBER='(25,0,0)';
      BIDIRECTIONAL='TRUE';
      INPUT_LOAD='(-0.01,0.01)';
      OUTPUT_LOAD='(1.0,-1.0)';
    'DQ13_A':
      PIN_NUMBER='(27,0,0)';
      BIDIRECTIONAL='TRUE';
      INPUT_LOAD='(-0.01,0.01)';
      OUTPUT_LOAD='(1.0,-1.0)';
    'DQ14_A':
      PIN_NUMBER='(170,0,0)';
      BIDIRECTIONAL='TRUE';
      INPUT_LOAD='(-0.01,0.01)';
      OUTPUT_LOAD='(1.0,-1.0)';
    'DQ15_A':
      PIN_NUMBER='(172,0,0)';
      BIDIRECTIONAL='TRUE';
      INPUT_LOAD='(-0.01,0.01)';
      OUTPUT_LOAD='(1.0,-1.0)';
    'DQ16_A':
      PIN_NUMBER='(29,0,0)';
      BIDIRECTIONAL='TRUE';
      INPUT_LOAD='(-0.01,0.01)';
      OUTPUT_LOAD='(1.0,-1.0)';
    'DQ17_A':
      PIN_NUMBER='(31,0,0)';
      BIDIRECTIONAL='TRUE';
      INPUT_LOAD='(-0.01,0.01)';
      OUTPUT_LOAD='(1.0,-1.0)';
    'DQ18_A':
      PIN_NUMBER='(174,0,0)';
      BIDIRECTIONAL='TRUE';
      INPUT_LOAD='(-0.01,0.01)';
      OUTPUT_LOAD='(1.0,-1.0)';
    'DQ19_A':
      PIN_NUMBER='(176,0,0)';
      BIDIRECTIONAL='TRUE';
      INPUT_LOAD='(-0.01,0.01)';
      OUTPUT_LOAD='(1.0,-1.0)';
    'DQ20_A':
      PIN_NUMBER='(36,0,0)';
      BIDIRECTIONAL='TRUE';
      INPUT_LOAD='(-0.01,0.01)';
      OUTPUT_LOAD='(1.0,-1.0)';
    'DQ21_A':
      PIN_NUMBER='(38,0,0)';
      BIDIRECTIONAL='TRUE';
      INPUT_LOAD='(-0.01,0.01)';
      OUTPUT_LOAD='(1.0,-1.0)';
    'DQ22_A':
      PIN_NUMBER='(181,0,0)';
      BIDIRECTIONAL='TRUE';
      INPUT_LOAD='(-0.01,0.01)';
      OUTPUT_LOAD='(1.0,-1.0)';
    'DQ23_A':
      PIN_NUMBER='(183,0,0)';
      BIDIRECTIONAL='TRUE';
      INPUT_LOAD='(-0.01,0.01)';
      OUTPUT_LOAD='(1.0,-1.0)';
    'DQ24_A':
      PIN_NUMBER='(40,0,0)';
      BIDIRECTIONAL='TRUE';
      INPUT_LOAD='(-0.01,0.01)';
      OUTPUT_LOAD='(1.0,-1.0)';
    'DQ25_A':
      PIN_NUMBER='(42,0,0)';
      BIDIRECTIONAL='TRUE';
      INPUT_LOAD='(-0.01,0.01)';
      OUTPUT_LOAD='(1.0,-1.0)';
    'DQ26_A':
      PIN_NUMBER='(185,0,0)';
      BIDIRECTIONAL='TRUE';
      INPUT_LOAD='(-0.01,0.01)';
      OUTPUT_LOAD='(1.0,-1.0)';
    'DQ27_A':
      PIN_NUMBER='(187,0,0)';
      BIDIRECTIONAL='TRUE';
      INPUT_LOAD='(-0.01,0.01)';
      OUTPUT_LOAD='(1.0,-1.0)';
    'DQ28_A':
      PIN_NUMBER='(47,0,0)';
      BIDIRECTIONAL='TRUE';
      INPUT_LOAD='(-0.01,0.01)';
      OUTPUT_LOAD='(1.0,-1.0)';
    'DQ29_A':
      PIN_NUMBER='(49,0,0)';
      BIDIRECTIONAL='TRUE';
      INPUT_LOAD='(-0.01,0.01)';
      OUTPUT_LOAD='(1.0,-1.0)';
    'DQ30_A':
      PIN_NUMBER='(192,0,0)';
      BIDIRECTIONAL='TRUE';
      INPUT_LOAD='(-0.01,0.01)';
      OUTPUT_LOAD='(1.0,-1.0)';
    '-CS1_B':
      PIN_NUMBER='(229,0,0)';
      INPUT_LOAD='(-0.01,0.01)';
    '-CS1_A':
      PIN_NUMBER='(209,0,0)';
      INPUT_LOAD='(-0.01,0.01)';
    '-CS0_B':
      PIN_NUMBER='(84,0,0)';
      INPUT_LOAD='(-0.01,0.01)';
    '-CS0_A':
      PIN_NUMBER='(64,0,0)';
      INPUT_LOAD='(-0.01,0.01)';
    'CK_T':
      PIN_NUMBER='(217,0,0)';
      INPUT_LOAD='(-0.01,0.01)';
    'CK_C':
      PIN_NUMBER='(218,0,0)';
      INPUT_LOAD='(-0.01,0.01)';
    'CB0_B':
      PIN_NUMBER='(96,0,0)';
      BIDIRECTIONAL='TRUE';
      INPUT_LOAD='(-0.01,0.01)';
      OUTPUT_LOAD='(1.0,-1.0)';
    'CB1_B':
      PIN_NUMBER='(98,0,0)';
      BIDIRECTIONAL='TRUE';
      INPUT_LOAD='(-0.01,0.01)';
      OUTPUT_LOAD='(1.0,-1.0)';
    'CB2_B':
      PIN_NUMBER='(241,0,0)';
      BIDIRECTIONAL='TRUE';
      INPUT_LOAD='(-0.01,0.01)';
      OUTPUT_LOAD='(1.0,-1.0)';
    'CB3_B':
      PIN_NUMBER='(243,0,0)';
      BIDIRECTIONAL='TRUE';
      INPUT_LOAD='(-0.01,0.01)';
      OUTPUT_LOAD='(1.0,-1.0)';
    'CB4_B':
      PIN_NUMBER='(89,0,0)';
      BIDIRECTIONAL='TRUE';
      INPUT_LOAD='(-0.01,0.01)';
      OUTPUT_LOAD='(1.0,-1.0)';
    'CB5_B':
      PIN_NUMBER='(91,0,0)';
      BIDIRECTIONAL='TRUE';
      INPUT_LOAD='(-0.01,0.01)';
      OUTPUT_LOAD='(1.0,-1.0)';
    'CB6_B':
      PIN_NUMBER='(234,0,0)';
      BIDIRECTIONAL='TRUE';
      INPUT_LOAD='(-0.01,0.01)';
      OUTPUT_LOAD='(1.0,-1.0)';
    'CB0_A':
      PIN_NUMBER='(51,0,0)';
      BIDIRECTIONAL='TRUE';
      INPUT_LOAD='(-0.01,0.01)';
      OUTPUT_LOAD='(1.0,-1.0)';
    'CB2_A':
      PIN_NUMBER='(196,0,0)';
      BIDIRECTIONAL='TRUE';
      INPUT_LOAD='(-0.01,0.01)';
      OUTPUT_LOAD='(1.0,-1.0)';
    'CB3_A':
      PIN_NUMBER='(198,0,0)';
      BIDIRECTIONAL='TRUE';
      INPUT_LOAD='(-0.01,0.01)';
      OUTPUT_LOAD='(1.0,-1.0)';
    'CB5_A':
      PIN_NUMBER='(60,0,0)';
      BIDIRECTIONAL='TRUE';
      INPUT_LOAD='(-0.01,0.01)';
      OUTPUT_LOAD='(1.0,-1.0)';
    'CB6_A':
      PIN_NUMBER='(203,0,0)';
      BIDIRECTIONAL='TRUE';
      INPUT_LOAD='(-0.01,0.01)';
      OUTPUT_LOAD='(1.0,-1.0)';
    'CA6_B':
      PIN_NUMBER='(82,0,0)';
      INPUT_LOAD='(-0.01,0.01)';
    'CA6_A':
      PIN_NUMBER='(72,0,0)';
      INPUT_LOAD='(-0.01,0.01)';
    'CA5_B':
      PIN_NUMBER='(225,0,0)';
      INPUT_LOAD='(-0.01,0.01)';
    'CA5_A':
      PIN_NUMBER='(215,0,0)';
      INPUT_LOAD='(-0.01,0.01)';
    'CA4_B':
      PIN_NUMBER='(80,0,0)';
      INPUT_LOAD='(-0.01,0.01)';
    'CA4_A':
      PIN_NUMBER='(70,0,0)';
      INPUT_LOAD='(-0.01,0.01)';
    'CA3_B':
      PIN_NUMBER='(223,0,0)';
      INPUT_LOAD='(-0.01,0.01)';
    'CA3_A':
      PIN_NUMBER='(213,0,0)';
      INPUT_LOAD='(-0.01,0.01)';
    'CA2_B':
      PIN_NUMBER='(78,0,0)';
      INPUT_LOAD='(-0.01,0.01)';
    'CA2_A':
      PIN_NUMBER='(68,0,0)';
      INPUT_LOAD='(-0.01,0.01)';
    'CA1_B':
      PIN_NUMBER='(221,0,0)';
      INPUT_LOAD='(-0.01,0.01)';
    'CA1_A':
      PIN_NUMBER='(211,0,0)';
      INPUT_LOAD='(-0.01,0.01)';
    'CA0_B':
      PIN_NUMBER='(76,0,0)';
      INPUT_LOAD='(-0.01,0.01)';
    'CA0_A':
      PIN_NUMBER='(66,0,0)';
      INPUT_LOAD='(-0.01,0.01)';
    '-ALERT':
      PIN_NUMBER='(62,0,0)';
      OUTPUT_LOAD='(1.0,-1.0)';
    'CB7_B':
      PIN_NUMBER='(236,0,0)';
      BIDIRECTIONAL='TRUE';
      INPUT_LOAD='(-0.01,0.01)';
      OUTPUT_LOAD='(1.0,-1.0)';
    'CB1_A':
      PIN_NUMBER='(53,0,0)';
      BIDIRECTIONAL='TRUE';
      INPUT_LOAD='(-0.01,0.01)';
      OUTPUT_LOAD='(1.0,-1.0)';
    'CB4_A':
      PIN_NUMBER='(58,0,0)';
      BIDIRECTIONAL='TRUE';
      INPUT_LOAD='(-0.01,0.01)';
      OUTPUT_LOAD='(1.0,-1.0)';
    'CB7_A':
      PIN_NUMBER='(205,0,0)';
      BIDIRECTIONAL='TRUE';
      INPUT_LOAD='(-0.01,0.01)';
      OUTPUT_LOAD='(1.0,-1.0)';
    'DQ31_A':
      PIN_NUMBER='(194,0,0)';
      BIDIRECTIONAL='TRUE';
      INPUT_LOAD='(-0.01,0.01)';
      OUTPUT_LOAD='(1.0,-1.0)';
    '-DQS9_B_T||TDQS9_B_T||DBI4_B':
      PIN_NUMBER='(0,93,0)';
      BIDIRECTIONAL='TRUE';
      INPUT_LOAD='(-0.01,0.01)';
      OUTPUT_LOAD='(1.0,-1.0)';
    'DQS9_B_C||TDQS9_B_C':
      PIN_NUMBER='(0,94,0)';
      BIDIRECTIONAL='TRUE';
      INPUT_LOAD='(-0.01,0.01)';
      OUTPUT_LOAD='(1.0,-1.0)';
    'DQS9_A_T||TDQS9_A_T':
      PIN_NUMBER='(0,201,0)';
      BIDIRECTIONAL='TRUE';
      INPUT_LOAD='(-0.01,0.01)';
      OUTPUT_LOAD='(1.0,-1.0)';
    'DQS9_A_C||TDQS9_A_C':
      PIN_NUMBER='(0,200,0)';
      BIDIRECTIONAL='TRUE';
      INPUT_LOAD='(-0.01,0.01)';
      OUTPUT_LOAD='(1.0,-1.0)';
    'DQS8_A_T||TDQS8_A_T':
      PIN_NUMBER='(0,190,0)';
      BIDIRECTIONAL='TRUE';
      INPUT_LOAD='(-0.01,0.01)';
      OUTPUT_LOAD='(1.0,-1.0)';
    'DQS8_A_C||TDQS8_A_C':
      PIN_NUMBER='(0,189,0)';
      BIDIRECTIONAL='TRUE';
      INPUT_LOAD='(-0.01,0.01)';
      OUTPUT_LOAD='(1.0,-1.0)';
    'DQS7_B_C||TDQS7_B_C':
      PIN_NUMBER='(0,271,0)';
      BIDIRECTIONAL='TRUE';
      INPUT_LOAD='(-0.01,0.01)';
      OUTPUT_LOAD='(1.0,-1.0)';
    'DQS7_A_T||TDQS7_A_T':
      PIN_NUMBER='(0,179,0)';
      BIDIRECTIONAL='TRUE';
      INPUT_LOAD='(-0.01,0.01)';
      OUTPUT_LOAD='(1.0,-1.0)';
    'DQS6_B_T||TDQS6_B_T':
      PIN_NUMBER='(0,261,0)';
      BIDIRECTIONAL='TRUE';
      INPUT_LOAD='(-0.01,0.01)';
      OUTPUT_LOAD='(1.0,-1.0)';
    'DQS6_B_C||TDQS6_B_C':
      PIN_NUMBER='(0,260,0)';
      BIDIRECTIONAL='TRUE';
      INPUT_LOAD='(-0.01,0.01)';
      OUTPUT_LOAD='(1.0,-1.0)';
    'DQS6_A_C||TDQS6_A_C||DQS6_A_T||TDQS6_A_T':
      PIN_NUMBER='(0,167,0)';
      BIDIRECTIONAL='TRUE';
      INPUT_LOAD='(-0.01,0.01)';
      OUTPUT_LOAD='(1.0,-1.0)';
    'DQS5_B_T||TDQS5_B_T':
      PIN_NUMBER='(0,250,0)';
      BIDIRECTIONAL='TRUE';
      INPUT_LOAD='(-0.01,0.01)';
      OUTPUT_LOAD='(1.0,-1.0)';
    'DQS5_B_C||TDQS5_B_C':
      PIN_NUMBER='(0,249,0)';
      BIDIRECTIONAL='TRUE';
      INPUT_LOAD='(-0.01,0.01)';
      OUTPUT_LOAD='(1.0,-1.0)';
    'DQS5_A_T||TDQS5_A_T':
      PIN_NUMBER='(0,157,0)';
      BIDIRECTIONAL='TRUE';
      INPUT_LOAD='(-0.01,0.01)';
      OUTPUT_LOAD='(1.0,-1.0)';
    'DQS5_A_C||TDQS5_A_C||DQS5_A_T||TDQS5_A_T':
      PIN_NUMBER='(0,156,0)';
      BIDIRECTIONAL='TRUE';
      INPUT_LOAD='(-0.01,0.01)';
      OUTPUT_LOAD='(1.0,-1.0)';
    'DQS4_B_T':
      PIN_NUMBER='(0,239,0)';
      BIDIRECTIONAL='TRUE';
      INPUT_LOAD='(-0.01,0.01)';
      OUTPUT_LOAD='(1.0,-1.0)';
    'DQS4_B_C':
      PIN_NUMBER='(0,238,0)';
      BIDIRECTIONAL='TRUE';
      INPUT_LOAD='(-0.01,0.01)';
      OUTPUT_LOAD='(1.0,-1.0)';
    'DQS4_A_T':
      PIN_NUMBER='(0,55,0)';
      BIDIRECTIONAL='TRUE';
      INPUT_LOAD='(-0.01,0.01)';
      OUTPUT_LOAD='(1.0,-1.0)';
    'DQS4_A_C':
      PIN_NUMBER='(0,56,0)';
      BIDIRECTIONAL='TRUE';
      INPUT_LOAD='(-0.01,0.01)';
      OUTPUT_LOAD='(1.0,-1.0)';
    'DQS3_B_T':
      PIN_NUMBER='(0,137,0)';
      BIDIRECTIONAL='TRUE';
      INPUT_LOAD='(-0.01,0.01)';
      OUTPUT_LOAD='(1.0,-1.0)';
    'DQS3_B_C':
      PIN_NUMBER='(0,138,0)';
      BIDIRECTIONAL='TRUE';
      INPUT_LOAD='(-0.01,0.01)';
      OUTPUT_LOAD='(1.0,-1.0)';
    'DQS3_A_T':
      PIN_NUMBER='(0,44,0)';
      BIDIRECTIONAL='TRUE';
      INPUT_LOAD='(-0.01,0.01)';
      OUTPUT_LOAD='(1.0,-1.0)';
    'DQS3_A_C':
      PIN_NUMBER='(0,45,0)';
      BIDIRECTIONAL='TRUE';
      INPUT_LOAD='(-0.01,0.01)';
      OUTPUT_LOAD='(1.0,-1.0)';
    'DQS2_B_T':
      PIN_NUMBER='(0,126,0)';
      BIDIRECTIONAL='TRUE';
      INPUT_LOAD='(-0.01,0.01)';
      OUTPUT_LOAD='(1.0,-1.0)';
    'DQS2_B_C':
      PIN_NUMBER='(0,127,0)';
      BIDIRECTIONAL='TRUE';
      INPUT_LOAD='(-0.01,0.01)';
      OUTPUT_LOAD='(1.0,-1.0)';
    'DQS2_A_T':
      PIN_NUMBER='(0,33,0)';
      BIDIRECTIONAL='TRUE';
      INPUT_LOAD='(-0.01,0.01)';
      OUTPUT_LOAD='(1.0,-1.0)';
    'DQS2_A_C':
      PIN_NUMBER='(0,34,0)';
      BIDIRECTIONAL='TRUE';
      INPUT_LOAD='(-0.01,0.01)';
      OUTPUT_LOAD='(1.0,-1.0)';
    'DQS1_B_T':
      PIN_NUMBER='(0,115,0)';
      BIDIRECTIONAL='TRUE';
      INPUT_LOAD='(-0.01,0.01)';
      OUTPUT_LOAD='(1.0,-1.0)';
    'DQS1_B_C':
      PIN_NUMBER='(0,116,0)';
      BIDIRECTIONAL='TRUE';
      INPUT_LOAD='(-0.01,0.01)';
      OUTPUT_LOAD='(1.0,-1.0)';
    'DQS1_A_T':
      PIN_NUMBER='(0,22,0)';
      BIDIRECTIONAL='TRUE';
      INPUT_LOAD='(-0.01,0.01)';
      OUTPUT_LOAD='(1.0,-1.0)';
    'DQS1_A_C':
      PIN_NUMBER='(0,23,0)';
      BIDIRECTIONAL='TRUE';
      INPUT_LOAD='(-0.01,0.01)';
      OUTPUT_LOAD='(1.0,-1.0)';
    'DQS0_B_T':
      PIN_NUMBER='(0,104,0)';
      BIDIRECTIONAL='TRUE';
      INPUT_LOAD='(-0.01,0.01)';
      OUTPUT_LOAD='(1.0,-1.0)';
    'DQS0_B_C':
      PIN_NUMBER='(0,105,0)';
      BIDIRECTIONAL='TRUE';
      INPUT_LOAD='(-0.01,0.01)';
      OUTPUT_LOAD='(1.0,-1.0)';
    'DQS0_A_T':
      PIN_NUMBER='(0,11,0)';
      BIDIRECTIONAL='TRUE';
      INPUT_LOAD='(-0.01,0.01)';
      OUTPUT_LOAD='(1.0,-1.0)';
    'DQS0_A_C':
      PIN_NUMBER='(0,12,0)';
      BIDIRECTIONAL='TRUE';
      INPUT_LOAD='(-0.01,0.01)';
      OUTPUT_LOAD='(1.0,-1.0)';
    'DQS7_B_T||TDQS7_B_T':
      PIN_NUMBER='(0,272,0)';
      BIDIRECTIONAL='TRUE';
      INPUT_LOAD='(-0.01,0.01)';
      OUTPUT_LOAD='(1.0,-1.0)';
    'DQS8_B_C||TDQS8_B_C':
      PIN_NUMBER='(0,282,0)';
      BIDIRECTIONAL='TRUE';
      INPUT_LOAD='(-0.01,0.01)';
      OUTPUT_LOAD='(1.0,-1.0)';
    'DQS8_B_T||TDQS8_B_T':
      PIN_NUMBER='(0,283,0)';
      BIDIRECTIONAL='TRUE';
      INPUT_LOAD='(-0.01,0.01)';
      OUTPUT_LOAD='(1.0,-1.0)';
    'DQS6_A_T||TDQS6_A_T':
      PIN_NUMBER='(0,168,0)';
      BIDIRECTIONAL='TRUE';
      INPUT_LOAD='(-0.01,0.01)';
      OUTPUT_LOAD='(1.0,-1.0)';
    'DQS7_A_C||TDQS7_A_C':
      PIN_NUMBER='(0,178,0)';
      BIDIRECTIONAL='TRUE';
      INPUT_LOAD='(-0.01,0.01)';
      OUTPUT_LOAD='(1.0,-1.0)';
    'VSS0':
      PIN_NUMBER='(0,0,6)';
      PINUSE='POWER';
      NO_LOAD_CHECK='Both';
      NO_IO_CHECK='Both';
      NO_ASSERT_CHECK='TRUE';
      NO_DIR_CHECK='TRUE';
      ALLOW_CONNECT='TRUE';
    'VSS1':
      PIN_NUMBER='(0,0,8)';
      PINUSE='POWER';
      NO_LOAD_CHECK='Both';
      NO_IO_CHECK='Both';
      NO_ASSERT_CHECK='TRUE';
      NO_DIR_CHECK='TRUE';
      ALLOW_CONNECT='TRUE';
    'VSS2':
      PIN_NUMBER='(0,0,10)';
      PINUSE='POWER';
      NO_LOAD_CHECK='Both';
      NO_IO_CHECK='Both';
      NO_ASSERT_CHECK='TRUE';
      NO_DIR_CHECK='TRUE';
      ALLOW_CONNECT='TRUE';
    'VSS3':
      PIN_NUMBER='(0,0,13)';
      PINUSE='POWER';
      NO_LOAD_CHECK='Both';
      NO_IO_CHECK='Both';
      NO_ASSERT_CHECK='TRUE';
      NO_DIR_CHECK='TRUE';
      ALLOW_CONNECT='TRUE';
    'VSS4':
      PIN_NUMBER='(0,0,15)';
      PINUSE='POWER';
      NO_LOAD_CHECK='Both';
      NO_IO_CHECK='Both';
      NO_ASSERT_CHECK='TRUE';
      NO_DIR_CHECK='TRUE';
      ALLOW_CONNECT='TRUE';
    'VSS5':
      PIN_NUMBER='(0,0,17)';
      PINUSE='POWER';
      NO_LOAD_CHECK='Both';
      NO_IO_CHECK='Both';
      NO_ASSERT_CHECK='TRUE';
      NO_DIR_CHECK='TRUE';
      ALLOW_CONNECT='TRUE';
    'VSS6':
      PIN_NUMBER='(0,0,19)';
      PINUSE='POWER';
      NO_LOAD_CHECK='Both';
      NO_IO_CHECK='Both';
      NO_ASSERT_CHECK='TRUE';
      NO_DIR_CHECK='TRUE';
      ALLOW_CONNECT='TRUE';
    'VSS7':
      PIN_NUMBER='(0,0,21)';
      PINUSE='POWER';
      NO_LOAD_CHECK='Both';
      NO_IO_CHECK='Both';
      NO_ASSERT_CHECK='TRUE';
      NO_DIR_CHECK='TRUE';
      ALLOW_CONNECT='TRUE';
    'VSS8':
      PIN_NUMBER='(0,0,24)';
      PINUSE='POWER';
      NO_LOAD_CHECK='Both';
      NO_IO_CHECK='Both';
      NO_ASSERT_CHECK='TRUE';
      NO_DIR_CHECK='TRUE';
      ALLOW_CONNECT='TRUE';
    'VSS9':
      PIN_NUMBER='(0,0,26)';
      PINUSE='POWER';
      NO_LOAD_CHECK='Both';
      NO_IO_CHECK='Both';
      NO_ASSERT_CHECK='TRUE';
      NO_DIR_CHECK='TRUE';
      ALLOW_CONNECT='TRUE';
    'VSS10':
      PIN_NUMBER='(0,0,28)';
      PINUSE='POWER';
      NO_LOAD_CHECK='Both';
      NO_IO_CHECK='Both';
      NO_ASSERT_CHECK='TRUE';
      NO_DIR_CHECK='TRUE';
      ALLOW_CONNECT='TRUE';
    'VSS11':
      PIN_NUMBER='(0,0,30)';
      PINUSE='POWER';
      NO_LOAD_CHECK='Both';
      NO_IO_CHECK='Both';
      NO_ASSERT_CHECK='TRUE';
      NO_DIR_CHECK='TRUE';
      ALLOW_CONNECT='TRUE';
    'VSS12':
      PIN_NUMBER='(0,0,32)';
      PINUSE='POWER';
      NO_LOAD_CHECK='Both';
      NO_IO_CHECK='Both';
      NO_ASSERT_CHECK='TRUE';
      NO_DIR_CHECK='TRUE';
      ALLOW_CONNECT='TRUE';
    'VSS13':
      PIN_NUMBER='(0,0,35)';
      PINUSE='POWER';
      NO_LOAD_CHECK='Both';
      NO_IO_CHECK='Both';
      NO_ASSERT_CHECK='TRUE';
      NO_DIR_CHECK='TRUE';
      ALLOW_CONNECT='TRUE';
    'VSS14':
      PIN_NUMBER='(0,0,37)';
      PINUSE='POWER';
      NO_LOAD_CHECK='Both';
      NO_IO_CHECK='Both';
      NO_ASSERT_CHECK='TRUE';
      NO_DIR_CHECK='TRUE';
      ALLOW_CONNECT='TRUE';
    'VSS15':
      PIN_NUMBER='(0,0,39)';
      PINUSE='POWER';
      NO_LOAD_CHECK='Both';
      NO_IO_CHECK='Both';
      NO_ASSERT_CHECK='TRUE';
      NO_DIR_CHECK='TRUE';
      ALLOW_CONNECT='TRUE';
    'VSS16':
      PIN_NUMBER='(0,0,41)';
      PINUSE='POWER';
      NO_LOAD_CHECK='Both';
      NO_IO_CHECK='Both';
      NO_ASSERT_CHECK='TRUE';
      NO_DIR_CHECK='TRUE';
      ALLOW_CONNECT='TRUE';
    'VSS17':
      PIN_NUMBER='(0,0,43)';
      PINUSE='POWER';
      NO_LOAD_CHECK='Both';
      NO_IO_CHECK='Both';
      NO_ASSERT_CHECK='TRUE';
      NO_DIR_CHECK='TRUE';
      ALLOW_CONNECT='TRUE';
    'VSS18':
      PIN_NUMBER='(0,0,46)';
      PINUSE='POWER';
      NO_LOAD_CHECK='Both';
      NO_IO_CHECK='Both';
      NO_ASSERT_CHECK='TRUE';
      NO_DIR_CHECK='TRUE';
      ALLOW_CONNECT='TRUE';
    'VSS19':
      PIN_NUMBER='(0,0,48)';
      PINUSE='POWER';
      NO_LOAD_CHECK='Both';
      NO_IO_CHECK='Both';
      NO_ASSERT_CHECK='TRUE';
      NO_DIR_CHECK='TRUE';
      ALLOW_CONNECT='TRUE';
    'VSS20':
      PIN_NUMBER='(0,0,50)';
      PINUSE='POWER';
      NO_LOAD_CHECK='Both';
      NO_IO_CHECK='Both';
      NO_ASSERT_CHECK='TRUE';
      NO_DIR_CHECK='TRUE';
      ALLOW_CONNECT='TRUE';
    'VSS21':
      PIN_NUMBER='(0,0,52)';
      PINUSE='POWER';
      NO_LOAD_CHECK='Both';
      NO_IO_CHECK='Both';
      NO_ASSERT_CHECK='TRUE';
      NO_DIR_CHECK='TRUE';
      ALLOW_CONNECT='TRUE';
    'VSS22':
      PIN_NUMBER='(0,0,54)';
      PINUSE='POWER';
      NO_LOAD_CHECK='Both';
      NO_IO_CHECK='Both';
      NO_ASSERT_CHECK='TRUE';
      NO_DIR_CHECK='TRUE';
      ALLOW_CONNECT='TRUE';
    'VSS23':
      PIN_NUMBER='(0,0,57)';
      PINUSE='POWER';
      NO_LOAD_CHECK='Both';
      NO_IO_CHECK='Both';
      NO_ASSERT_CHECK='TRUE';
      NO_DIR_CHECK='TRUE';
      ALLOW_CONNECT='TRUE';
    'VSS24':
      PIN_NUMBER='(0,0,59)';
      PINUSE='POWER';
      NO_LOAD_CHECK='Both';
      NO_IO_CHECK='Both';
      NO_ASSERT_CHECK='TRUE';
      NO_DIR_CHECK='TRUE';
      ALLOW_CONNECT='TRUE';
    'VSS25':
      PIN_NUMBER='(0,0,61)';
      PINUSE='POWER';
      NO_LOAD_CHECK='Both';
      NO_IO_CHECK='Both';
      NO_ASSERT_CHECK='TRUE';
      NO_DIR_CHECK='TRUE';
      ALLOW_CONNECT='TRUE';
    'VSS26':
      PIN_NUMBER='(0,0,63)';
      PINUSE='POWER';
      NO_LOAD_CHECK='Both';
      NO_IO_CHECK='Both';
      NO_ASSERT_CHECK='TRUE';
      NO_DIR_CHECK='TRUE';
      ALLOW_CONNECT='TRUE';
    'VSS27':
      PIN_NUMBER='(0,0,65)';
      PINUSE='POWER';
      NO_LOAD_CHECK='Both';
      NO_IO_CHECK='Both';
      NO_ASSERT_CHECK='TRUE';
      NO_DIR_CHECK='TRUE';
      ALLOW_CONNECT='TRUE';
    'VSS28':
      PIN_NUMBER='(0,0,67)';
      PINUSE='POWER';
      NO_LOAD_CHECK='Both';
      NO_IO_CHECK='Both';
      NO_ASSERT_CHECK='TRUE';
      NO_DIR_CHECK='TRUE';
      ALLOW_CONNECT='TRUE';
    'VSS29':
      PIN_NUMBER='(0,0,69)';
      PINUSE='POWER';
      NO_LOAD_CHECK='Both';
      NO_IO_CHECK='Both';
      NO_ASSERT_CHECK='TRUE';
      NO_DIR_CHECK='TRUE';
      ALLOW_CONNECT='TRUE';
    'VSS30':
      PIN_NUMBER='(0,0,71)';
      PINUSE='POWER';
      NO_LOAD_CHECK='Both';
      NO_IO_CHECK='Both';
      NO_ASSERT_CHECK='TRUE';
      NO_DIR_CHECK='TRUE';
      ALLOW_CONNECT='TRUE';
    'VSS31':
      PIN_NUMBER='(0,0,73)';
      PINUSE='POWER';
      NO_LOAD_CHECK='Both';
      NO_IO_CHECK='Both';
      NO_ASSERT_CHECK='TRUE';
      NO_DIR_CHECK='TRUE';
      ALLOW_CONNECT='TRUE';
    'VSS32':
      PIN_NUMBER='(0,0,75)';
      PINUSE='POWER';
      NO_LOAD_CHECK='Both';
      NO_IO_CHECK='Both';
      NO_ASSERT_CHECK='TRUE';
      NO_DIR_CHECK='TRUE';
      ALLOW_CONNECT='TRUE';
    'VSS33':
      PIN_NUMBER='(0,0,77)';
      PINUSE='POWER';
      NO_LOAD_CHECK='Both';
      NO_IO_CHECK='Both';
      NO_ASSERT_CHECK='TRUE';
      NO_DIR_CHECK='TRUE';
      ALLOW_CONNECT='TRUE';
    'VSS34':
      PIN_NUMBER='(0,0,79)';
      PINUSE='POWER';
      NO_LOAD_CHECK='Both';
      NO_IO_CHECK='Both';
      NO_ASSERT_CHECK='TRUE';
      NO_DIR_CHECK='TRUE';
      ALLOW_CONNECT='TRUE';
    'VSS35':
      PIN_NUMBER='(0,0,81)';
      PINUSE='POWER';
      NO_LOAD_CHECK='Both';
      NO_IO_CHECK='Both';
      NO_ASSERT_CHECK='TRUE';
      NO_DIR_CHECK='TRUE';
      ALLOW_CONNECT='TRUE';
    'VSS36':
      PIN_NUMBER='(0,0,83)';
      PINUSE='POWER';
      NO_LOAD_CHECK='Both';
      NO_IO_CHECK='Both';
      NO_ASSERT_CHECK='TRUE';
      NO_DIR_CHECK='TRUE';
      ALLOW_CONNECT='TRUE';
    'VSS37':
      PIN_NUMBER='(0,0,85)';
      PINUSE='POWER';
      NO_LOAD_CHECK='Both';
      NO_IO_CHECK='Both';
      NO_ASSERT_CHECK='TRUE';
      NO_DIR_CHECK='TRUE';
      ALLOW_CONNECT='TRUE';
    'VSS38':
      PIN_NUMBER='(0,0,88)';
      PINUSE='POWER';
      NO_LOAD_CHECK='Both';
      NO_IO_CHECK='Both';
      NO_ASSERT_CHECK='TRUE';
      NO_DIR_CHECK='TRUE';
      ALLOW_CONNECT='TRUE';
    'VSS39':
      PIN_NUMBER='(0,0,90)';
      PINUSE='POWER';
      NO_LOAD_CHECK='Both';
      NO_IO_CHECK='Both';
      NO_ASSERT_CHECK='TRUE';
      NO_DIR_CHECK='TRUE';
      ALLOW_CONNECT='TRUE';
    'VSS40':
      PIN_NUMBER='(0,0,92)';
      PINUSE='POWER';
      NO_LOAD_CHECK='Both';
      NO_IO_CHECK='Both';
      NO_ASSERT_CHECK='TRUE';
      NO_DIR_CHECK='TRUE';
      ALLOW_CONNECT='TRUE';
    'VSS41':
      PIN_NUMBER='(0,0,95)';
      PINUSE='POWER';
      NO_LOAD_CHECK='Both';
      NO_IO_CHECK='Both';
      NO_ASSERT_CHECK='TRUE';
      NO_DIR_CHECK='TRUE';
      ALLOW_CONNECT='TRUE';
    'VSS42':
      PIN_NUMBER='(0,0,97)';
      PINUSE='POWER';
      NO_LOAD_CHECK='Both';
      NO_IO_CHECK='Both';
      NO_ASSERT_CHECK='TRUE';
      NO_DIR_CHECK='TRUE';
      ALLOW_CONNECT='TRUE';
    'VSS43':
      PIN_NUMBER='(0,0,99)';
      PINUSE='POWER';
      NO_LOAD_CHECK='Both';
      NO_IO_CHECK='Both';
      NO_ASSERT_CHECK='TRUE';
      NO_DIR_CHECK='TRUE';
      ALLOW_CONNECT='TRUE';
    'VSS44':
      PIN_NUMBER='(0,0,101)';
      PINUSE='POWER';
      NO_LOAD_CHECK='Both';
      NO_IO_CHECK='Both';
      NO_ASSERT_CHECK='TRUE';
      NO_DIR_CHECK='TRUE';
      ALLOW_CONNECT='TRUE';
    'VSS45':
      PIN_NUMBER='(0,0,103)';
      PINUSE='POWER';
      NO_LOAD_CHECK='Both';
      NO_IO_CHECK='Both';
      NO_ASSERT_CHECK='TRUE';
      NO_DIR_CHECK='TRUE';
      ALLOW_CONNECT='TRUE';
    'VSS46':
      PIN_NUMBER='(0,0,106)';
      PINUSE='POWER';
      NO_LOAD_CHECK='Both';
      NO_IO_CHECK='Both';
      NO_ASSERT_CHECK='TRUE';
      NO_DIR_CHECK='TRUE';
      ALLOW_CONNECT='TRUE';
    'VSS47':
      PIN_NUMBER='(0,0,108)';
      PINUSE='POWER';
      NO_LOAD_CHECK='Both';
      NO_IO_CHECK='Both';
      NO_ASSERT_CHECK='TRUE';
      NO_DIR_CHECK='TRUE';
      ALLOW_CONNECT='TRUE';
    'VSS48':
      PIN_NUMBER='(0,0,110)';
      PINUSE='POWER';
      NO_LOAD_CHECK='Both';
      NO_IO_CHECK='Both';
      NO_ASSERT_CHECK='TRUE';
      NO_DIR_CHECK='TRUE';
      ALLOW_CONNECT='TRUE';
    'VSS49':
      PIN_NUMBER='(0,0,112)';
      PINUSE='POWER';
      NO_LOAD_CHECK='Both';
      NO_IO_CHECK='Both';
      NO_ASSERT_CHECK='TRUE';
      NO_DIR_CHECK='TRUE';
      ALLOW_CONNECT='TRUE';
    'VSS50':
      PIN_NUMBER='(0,0,114)';
      PINUSE='POWER';
      NO_LOAD_CHECK='Both';
      NO_IO_CHECK='Both';
      NO_ASSERT_CHECK='TRUE';
      NO_DIR_CHECK='TRUE';
      ALLOW_CONNECT='TRUE';
    'VSS51':
      PIN_NUMBER='(0,0,117)';
      PINUSE='POWER';
      NO_LOAD_CHECK='Both';
      NO_IO_CHECK='Both';
      NO_ASSERT_CHECK='TRUE';
      NO_DIR_CHECK='TRUE';
      ALLOW_CONNECT='TRUE';
    'VSS52':
      PIN_NUMBER='(0,0,119)';
      PINUSE='POWER';
      NO_LOAD_CHECK='Both';
      NO_IO_CHECK='Both';
      NO_ASSERT_CHECK='TRUE';
      NO_DIR_CHECK='TRUE';
      ALLOW_CONNECT='TRUE';
    'VSS53':
      PIN_NUMBER='(0,0,121)';
      PINUSE='POWER';
      NO_LOAD_CHECK='Both';
      NO_IO_CHECK='Both';
      NO_ASSERT_CHECK='TRUE';
      NO_DIR_CHECK='TRUE';
      ALLOW_CONNECT='TRUE';
    'VSS54':
      PIN_NUMBER='(0,0,123)';
      PINUSE='POWER';
      NO_LOAD_CHECK='Both';
      NO_IO_CHECK='Both';
      NO_ASSERT_CHECK='TRUE';
      NO_DIR_CHECK='TRUE';
      ALLOW_CONNECT='TRUE';
    'VSS55':
      PIN_NUMBER='(0,0,125)';
      PINUSE='POWER';
      NO_LOAD_CHECK='Both';
      NO_IO_CHECK='Both';
      NO_ASSERT_CHECK='TRUE';
      NO_DIR_CHECK='TRUE';
      ALLOW_CONNECT='TRUE';
    'VSS56':
      PIN_NUMBER='(0,0,128)';
      PINUSE='POWER';
      NO_LOAD_CHECK='Both';
      NO_IO_CHECK='Both';
      NO_ASSERT_CHECK='TRUE';
      NO_DIR_CHECK='TRUE';
      ALLOW_CONNECT='TRUE';
    'VSS57':
      PIN_NUMBER='(0,0,130)';
      PINUSE='POWER';
      NO_LOAD_CHECK='Both';
      NO_IO_CHECK='Both';
      NO_ASSERT_CHECK='TRUE';
      NO_DIR_CHECK='TRUE';
      ALLOW_CONNECT='TRUE';
    'VSS59':
      PIN_NUMBER='(0,0,134)';
      PINUSE='POWER';
      NO_LOAD_CHECK='Both';
      NO_IO_CHECK='Both';
      NO_ASSERT_CHECK='TRUE';
      NO_DIR_CHECK='TRUE';
      ALLOW_CONNECT='TRUE';
    'VSS63':
      PIN_NUMBER='(0,0,143)';
      PINUSE='POWER';
      NO_LOAD_CHECK='Both';
      NO_IO_CHECK='Both';
      NO_ASSERT_CHECK='TRUE';
      NO_DIR_CHECK='TRUE';
      ALLOW_CONNECT='TRUE';
    'VSS64':
      PIN_NUMBER='(0,0,151)';
      PINUSE='POWER';
      NO_LOAD_CHECK='Both';
      NO_IO_CHECK='Both';
      NO_ASSERT_CHECK='TRUE';
      NO_DIR_CHECK='TRUE';
      ALLOW_CONNECT='TRUE';
    'VSS65':
      PIN_NUMBER='(0,0,153)';
      PINUSE='POWER';
      NO_LOAD_CHECK='Both';
      NO_IO_CHECK='Both';
      NO_ASSERT_CHECK='TRUE';
      NO_DIR_CHECK='TRUE';
      ALLOW_CONNECT='TRUE';
    'VSS66':
      PIN_NUMBER='(0,0,155)';
      PINUSE='POWER';
      NO_LOAD_CHECK='Both';
      NO_IO_CHECK='Both';
      NO_ASSERT_CHECK='TRUE';
      NO_DIR_CHECK='TRUE';
      ALLOW_CONNECT='TRUE';
    'VSS67':
      PIN_NUMBER='(0,0,158)';
      PINUSE='POWER';
      NO_LOAD_CHECK='Both';
      NO_IO_CHECK='Both';
      NO_ASSERT_CHECK='TRUE';
      NO_DIR_CHECK='TRUE';
      ALLOW_CONNECT='TRUE';
    'VSS68':
      PIN_NUMBER='(0,0,160)';
      PINUSE='POWER';
      NO_LOAD_CHECK='Both';
      NO_IO_CHECK='Both';
      NO_ASSERT_CHECK='TRUE';
      NO_DIR_CHECK='TRUE';
      ALLOW_CONNECT='TRUE';
    'VSS69':
      PIN_NUMBER='(0,0,162)';
      PINUSE='POWER';
      NO_LOAD_CHECK='Both';
      NO_IO_CHECK='Both';
      NO_ASSERT_CHECK='TRUE';
      NO_DIR_CHECK='TRUE';
      ALLOW_CONNECT='TRUE';
    'VSS70':
      PIN_NUMBER='(0,0,164)';
      PINUSE='POWER';
      NO_LOAD_CHECK='Both';
      NO_IO_CHECK='Both';
      NO_ASSERT_CHECK='TRUE';
      NO_DIR_CHECK='TRUE';
      ALLOW_CONNECT='TRUE';
    'VSS71':
      PIN_NUMBER='(0,0,166)';
      PINUSE='POWER';
      NO_LOAD_CHECK='Both';
      NO_IO_CHECK='Both';
      NO_ASSERT_CHECK='TRUE';
      NO_DIR_CHECK='TRUE';
      ALLOW_CONNECT='TRUE';
    'VSS72':
      PIN_NUMBER='(0,0,169)';
      PINUSE='POWER';
      NO_LOAD_CHECK='Both';
      NO_IO_CHECK='Both';
      NO_ASSERT_CHECK='TRUE';
      NO_DIR_CHECK='TRUE';
      ALLOW_CONNECT='TRUE';
    'VSS73':
      PIN_NUMBER='(0,0,171)';
      PINUSE='POWER';
      NO_LOAD_CHECK='Both';
      NO_IO_CHECK='Both';
      NO_ASSERT_CHECK='TRUE';
      NO_DIR_CHECK='TRUE';
      ALLOW_CONNECT='TRUE';
    'VSS74':
      PIN_NUMBER='(0,0,173)';
      PINUSE='POWER';
      NO_LOAD_CHECK='Both';
      NO_IO_CHECK='Both';
      NO_ASSERT_CHECK='TRUE';
      NO_DIR_CHECK='TRUE';
      ALLOW_CONNECT='TRUE';
    'VSS75':
      PIN_NUMBER='(0,0,175)';
      PINUSE='POWER';
      NO_LOAD_CHECK='Both';
      NO_IO_CHECK='Both';
      NO_ASSERT_CHECK='TRUE';
      NO_DIR_CHECK='TRUE';
      ALLOW_CONNECT='TRUE';
    'VSS76':
      PIN_NUMBER='(0,0,177)';
      PINUSE='POWER';
      NO_LOAD_CHECK='Both';
      NO_IO_CHECK='Both';
      NO_ASSERT_CHECK='TRUE';
      NO_DIR_CHECK='TRUE';
      ALLOW_CONNECT='TRUE';
    'VSS77':
      PIN_NUMBER='(0,0,180)';
      PINUSE='POWER';
      NO_LOAD_CHECK='Both';
      NO_IO_CHECK='Both';
      NO_ASSERT_CHECK='TRUE';
      NO_DIR_CHECK='TRUE';
      ALLOW_CONNECT='TRUE';
    'VSS78':
      PIN_NUMBER='(0,0,182)';
      PINUSE='POWER';
      NO_LOAD_CHECK='Both';
      NO_IO_CHECK='Both';
      NO_ASSERT_CHECK='TRUE';
      NO_DIR_CHECK='TRUE';
      ALLOW_CONNECT='TRUE';
    'VSS79':
      PIN_NUMBER='(0,0,184)';
      PINUSE='POWER';
      NO_LOAD_CHECK='Both';
      NO_IO_CHECK='Both';
      NO_ASSERT_CHECK='TRUE';
      NO_DIR_CHECK='TRUE';
      ALLOW_CONNECT='TRUE';
    'VSS80':
      PIN_NUMBER='(0,0,186)';
      PINUSE='POWER';
      NO_LOAD_CHECK='Both';
      NO_IO_CHECK='Both';
      NO_ASSERT_CHECK='TRUE';
      NO_DIR_CHECK='TRUE';
      ALLOW_CONNECT='TRUE';
    'VSS81':
      PIN_NUMBER='(0,0,188)';
      PINUSE='POWER';
      NO_LOAD_CHECK='Both';
      NO_IO_CHECK='Both';
      NO_ASSERT_CHECK='TRUE';
      NO_DIR_CHECK='TRUE';
      ALLOW_CONNECT='TRUE';
    'VSS82':
      PIN_NUMBER='(0,0,191)';
      PINUSE='POWER';
      NO_LOAD_CHECK='Both';
      NO_IO_CHECK='Both';
      NO_ASSERT_CHECK='TRUE';
      NO_DIR_CHECK='TRUE';
      ALLOW_CONNECT='TRUE';
    'VSS83':
      PIN_NUMBER='(0,0,193)';
      PINUSE='POWER';
      NO_LOAD_CHECK='Both';
      NO_IO_CHECK='Both';
      NO_ASSERT_CHECK='TRUE';
      NO_DIR_CHECK='TRUE';
      ALLOW_CONNECT='TRUE';
    'VSS84':
      PIN_NUMBER='(0,0,195)';
      PINUSE='POWER';
      NO_LOAD_CHECK='Both';
      NO_IO_CHECK='Both';
      NO_ASSERT_CHECK='TRUE';
      NO_DIR_CHECK='TRUE';
      ALLOW_CONNECT='TRUE';
    'VSS85':
      PIN_NUMBER='(0,0,197)';
      PINUSE='POWER';
      NO_LOAD_CHECK='Both';
      NO_IO_CHECK='Both';
      NO_ASSERT_CHECK='TRUE';
      NO_DIR_CHECK='TRUE';
      ALLOW_CONNECT='TRUE';
    'VSS86':
      PIN_NUMBER='(0,0,199)';
      PINUSE='POWER';
      NO_LOAD_CHECK='Both';
      NO_IO_CHECK='Both';
      NO_ASSERT_CHECK='TRUE';
      NO_DIR_CHECK='TRUE';
      ALLOW_CONNECT='TRUE';
    'VSS87':
      PIN_NUMBER='(0,0,202)';
      PINUSE='POWER';
      NO_LOAD_CHECK='Both';
      NO_IO_CHECK='Both';
      NO_ASSERT_CHECK='TRUE';
      NO_DIR_CHECK='TRUE';
      ALLOW_CONNECT='TRUE';
    'VSS88':
      PIN_NUMBER='(0,0,204)';
      PINUSE='POWER';
      NO_LOAD_CHECK='Both';
      NO_IO_CHECK='Both';
      NO_ASSERT_CHECK='TRUE';
      NO_DIR_CHECK='TRUE';
      ALLOW_CONNECT='TRUE';
    'VSS89':
      PIN_NUMBER='(0,0,206)';
      PINUSE='POWER';
      NO_LOAD_CHECK='Both';
      NO_IO_CHECK='Both';
      NO_ASSERT_CHECK='TRUE';
      NO_DIR_CHECK='TRUE';
      ALLOW_CONNECT='TRUE';
    'VSS90':
      PIN_NUMBER='(0,0,208)';
      PINUSE='POWER';
      NO_LOAD_CHECK='Both';
      NO_IO_CHECK='Both';
      NO_ASSERT_CHECK='TRUE';
      NO_DIR_CHECK='TRUE';
      ALLOW_CONNECT='TRUE';
    'VSS91':
      PIN_NUMBER='(0,0,210)';
      PINUSE='POWER';
      NO_LOAD_CHECK='Both';
      NO_IO_CHECK='Both';
      NO_ASSERT_CHECK='TRUE';
      NO_DIR_CHECK='TRUE';
      ALLOW_CONNECT='TRUE';
    'VSS92':
      PIN_NUMBER='(0,0,212)';
      PINUSE='POWER';
      NO_LOAD_CHECK='Both';
      NO_IO_CHECK='Both';
      NO_ASSERT_CHECK='TRUE';
      NO_DIR_CHECK='TRUE';
      ALLOW_CONNECT='TRUE';
    'VSS93':
      PIN_NUMBER='(0,0,214)';
      PINUSE='POWER';
      NO_LOAD_CHECK='Both';
      NO_IO_CHECK='Both';
      NO_ASSERT_CHECK='TRUE';
      NO_DIR_CHECK='TRUE';
      ALLOW_CONNECT='TRUE';
    'VSS94':
      PIN_NUMBER='(0,0,216)';
      PINUSE='POWER';
      NO_LOAD_CHECK='Both';
      NO_IO_CHECK='Both';
      NO_ASSERT_CHECK='TRUE';
      NO_DIR_CHECK='TRUE';
      ALLOW_CONNECT='TRUE';
    'VSS95':
      PIN_NUMBER='(0,0,219)';
      PINUSE='POWER';
      NO_LOAD_CHECK='Both';
      NO_IO_CHECK='Both';
      NO_ASSERT_CHECK='TRUE';
      NO_DIR_CHECK='TRUE';
      ALLOW_CONNECT='TRUE';
    'VSS96':
      PIN_NUMBER='(0,0,222)';
      PINUSE='POWER';
      NO_LOAD_CHECK='Both';
      NO_IO_CHECK='Both';
      NO_ASSERT_CHECK='TRUE';
      NO_DIR_CHECK='TRUE';
      ALLOW_CONNECT='TRUE';
    'VSS97':
      PIN_NUMBER='(0,0,224)';
      PINUSE='POWER';
      NO_LOAD_CHECK='Both';
      NO_IO_CHECK='Both';
      NO_ASSERT_CHECK='TRUE';
      NO_DIR_CHECK='TRUE';
      ALLOW_CONNECT='TRUE';
    'VSS98':
      PIN_NUMBER='(0,0,226)';
      PINUSE='POWER';
      NO_LOAD_CHECK='Both';
      NO_IO_CHECK='Both';
      NO_ASSERT_CHECK='TRUE';
      NO_DIR_CHECK='TRUE';
      ALLOW_CONNECT='TRUE';
    'VSS99':
      PIN_NUMBER='(0,0,228)';
      PINUSE='POWER';
      NO_LOAD_CHECK='Both';
      NO_IO_CHECK='Both';
      NO_ASSERT_CHECK='TRUE';
      NO_DIR_CHECK='TRUE';
      ALLOW_CONNECT='TRUE';
    'VSS101':
      PIN_NUMBER='(0,0,233)';
      PINUSE='POWER';
      NO_LOAD_CHECK='Both';
      NO_IO_CHECK='Both';
      NO_ASSERT_CHECK='TRUE';
      NO_DIR_CHECK='TRUE';
      ALLOW_CONNECT='TRUE';
    'VSS103':
      PIN_NUMBER='(0,0,237)';
      PINUSE='POWER';
      NO_LOAD_CHECK='Both';
      NO_IO_CHECK='Both';
      NO_ASSERT_CHECK='TRUE';
      NO_DIR_CHECK='TRUE';
      ALLOW_CONNECT='TRUE';
    'VSS105':
      PIN_NUMBER='(0,0,242)';
      PINUSE='POWER';
      NO_LOAD_CHECK='Both';
      NO_IO_CHECK='Both';
      NO_ASSERT_CHECK='TRUE';
      NO_DIR_CHECK='TRUE';
      ALLOW_CONNECT='TRUE';
    'VSS106':
      PIN_NUMBER='(0,0,244)';
      PINUSE='POWER';
      NO_LOAD_CHECK='Both';
      NO_IO_CHECK='Both';
      NO_ASSERT_CHECK='TRUE';
      NO_DIR_CHECK='TRUE';
      ALLOW_CONNECT='TRUE';
    'VSS107':
      PIN_NUMBER='(0,0,246)';
      PINUSE='POWER';
      NO_LOAD_CHECK='Both';
      NO_IO_CHECK='Both';
      NO_ASSERT_CHECK='TRUE';
      NO_DIR_CHECK='TRUE';
      ALLOW_CONNECT='TRUE';
    'VSS108':
      PIN_NUMBER='(0,0,248)';
      PINUSE='POWER';
      NO_LOAD_CHECK='Both';
      NO_IO_CHECK='Both';
      NO_ASSERT_CHECK='TRUE';
      NO_DIR_CHECK='TRUE';
      ALLOW_CONNECT='TRUE';
    'VSS109':
      PIN_NUMBER='(0,0,251)';
      PINUSE='POWER';
      NO_LOAD_CHECK='Both';
      NO_IO_CHECK='Both';
      NO_ASSERT_CHECK='TRUE';
      NO_DIR_CHECK='TRUE';
      ALLOW_CONNECT='TRUE';
    'VSS110':
      PIN_NUMBER='(0,0,253)';
      PINUSE='POWER';
      NO_LOAD_CHECK='Both';
      NO_IO_CHECK='Both';
      NO_ASSERT_CHECK='TRUE';
      NO_DIR_CHECK='TRUE';
      ALLOW_CONNECT='TRUE';
    'VSS111':
      PIN_NUMBER='(0,0,255)';
      PINUSE='POWER';
      NO_LOAD_CHECK='Both';
      NO_IO_CHECK='Both';
      NO_ASSERT_CHECK='TRUE';
      NO_DIR_CHECK='TRUE';
      ALLOW_CONNECT='TRUE';
    'VSS112':
      PIN_NUMBER='(0,0,257)';
      PINUSE='POWER';
      NO_LOAD_CHECK='Both';
      NO_IO_CHECK='Both';
      NO_ASSERT_CHECK='TRUE';
      NO_DIR_CHECK='TRUE';
      ALLOW_CONNECT='TRUE';
    'VSS113':
      PIN_NUMBER='(0,0,259)';
      PINUSE='POWER';
      NO_LOAD_CHECK='Both';
      NO_IO_CHECK='Both';
      NO_ASSERT_CHECK='TRUE';
      NO_DIR_CHECK='TRUE';
      ALLOW_CONNECT='TRUE';
    'VSS114':
      PIN_NUMBER='(0,0,262)';
      PINUSE='POWER';
      NO_LOAD_CHECK='Both';
      NO_IO_CHECK='Both';
      NO_ASSERT_CHECK='TRUE';
      NO_DIR_CHECK='TRUE';
      ALLOW_CONNECT='TRUE';
    'VSS115':
      PIN_NUMBER='(0,0,264)';
      PINUSE='POWER';
      NO_LOAD_CHECK='Both';
      NO_IO_CHECK='Both';
      NO_ASSERT_CHECK='TRUE';
      NO_DIR_CHECK='TRUE';
      ALLOW_CONNECT='TRUE';
    'VSS116':
      PIN_NUMBER='(0,0,266)';
      PINUSE='POWER';
      NO_LOAD_CHECK='Both';
      NO_IO_CHECK='Both';
      NO_ASSERT_CHECK='TRUE';
      NO_DIR_CHECK='TRUE';
      ALLOW_CONNECT='TRUE';
    'VSS117':
      PIN_NUMBER='(0,0,268)';
      PINUSE='POWER';
      NO_LOAD_CHECK='Both';
      NO_IO_CHECK='Both';
      NO_ASSERT_CHECK='TRUE';
      NO_DIR_CHECK='TRUE';
      ALLOW_CONNECT='TRUE';
    'VSS118':
      PIN_NUMBER='(0,0,270)';
      PINUSE='POWER';
      NO_LOAD_CHECK='Both';
      NO_IO_CHECK='Both';
      NO_ASSERT_CHECK='TRUE';
      NO_DIR_CHECK='TRUE';
      ALLOW_CONNECT='TRUE';
    'VSS119':
      PIN_NUMBER='(0,0,273)';
      PINUSE='POWER';
      NO_LOAD_CHECK='Both';
      NO_IO_CHECK='Both';
      NO_ASSERT_CHECK='TRUE';
      NO_DIR_CHECK='TRUE';
      ALLOW_CONNECT='TRUE';
    'VSS120':
      PIN_NUMBER='(0,0,275)';
      PINUSE='POWER';
      NO_LOAD_CHECK='Both';
      NO_IO_CHECK='Both';
      NO_ASSERT_CHECK='TRUE';
      NO_DIR_CHECK='TRUE';
      ALLOW_CONNECT='TRUE';
    'VSS121':
      PIN_NUMBER='(0,0,277)';
      PINUSE='POWER';
      NO_LOAD_CHECK='Both';
      NO_IO_CHECK='Both';
      NO_ASSERT_CHECK='TRUE';
      NO_DIR_CHECK='TRUE';
      ALLOW_CONNECT='TRUE';
    'VSS122':
      PIN_NUMBER='(0,0,279)';
      PINUSE='POWER';
      NO_LOAD_CHECK='Both';
      NO_IO_CHECK='Both';
      NO_ASSERT_CHECK='TRUE';
      NO_DIR_CHECK='TRUE';
      ALLOW_CONNECT='TRUE';
    'VSS123':
      PIN_NUMBER='(0,0,281)';
      PINUSE='POWER';
      NO_LOAD_CHECK='Both';
      NO_IO_CHECK='Both';
      NO_ASSERT_CHECK='TRUE';
      NO_DIR_CHECK='TRUE';
      ALLOW_CONNECT='TRUE';
    'VSS124':
      PIN_NUMBER='(0,0,284)';
      PINUSE='POWER';
      NO_LOAD_CHECK='Both';
      NO_IO_CHECK='Both';
      NO_ASSERT_CHECK='TRUE';
      NO_DIR_CHECK='TRUE';
      ALLOW_CONNECT='TRUE';
    'VSS125':
      PIN_NUMBER='(0,0,286)';
      PINUSE='POWER';
      NO_LOAD_CHECK='Both';
      NO_IO_CHECK='Both';
      NO_ASSERT_CHECK='TRUE';
      NO_DIR_CHECK='TRUE';
      ALLOW_CONNECT='TRUE';
    'VSS126':
      PIN_NUMBER='(0,0,288)';
      PINUSE='POWER';
      NO_LOAD_CHECK='Both';
      NO_IO_CHECK='Both';
      NO_ASSERT_CHECK='TRUE';
      NO_DIR_CHECK='TRUE';
      ALLOW_CONNECT='TRUE';
    'VIN_BULK0':
      PIN_NUMBER='(0,0,1)';
      PINUSE='POWER';
      NO_LOAD_CHECK='Both';
      NO_IO_CHECK='Both';
      NO_ASSERT_CHECK='TRUE';
      NO_DIR_CHECK='TRUE';
      ALLOW_CONNECT='TRUE';
    'VIN_BULK1':
      PIN_NUMBER='(0,0,145)';
      PINUSE='POWER';
      NO_LOAD_CHECK='Both';
      NO_IO_CHECK='Both';
      NO_ASSERT_CHECK='TRUE';
      NO_DIR_CHECK='TRUE';
      ALLOW_CONNECT='TRUE';
    'VIN_BULK2':
      PIN_NUMBER='(0,0,146)';
      PINUSE='POWER';
      NO_LOAD_CHECK='Both';
      NO_IO_CHECK='Both';
      NO_ASSERT_CHECK='TRUE';
      NO_DIR_CHECK='TRUE';
      ALLOW_CONNECT='TRUE';
    'VSS100':
      PIN_NUMBER='(0,0,230)';
      PINUSE='POWER';
      NO_LOAD_CHECK='Both';
      NO_IO_CHECK='Both';
      NO_ASSERT_CHECK='TRUE';
      NO_DIR_CHECK='TRUE';
      ALLOW_CONNECT='TRUE';
    'VSS102':
      PIN_NUMBER='(0,0,235)';
      PINUSE='POWER';
      NO_LOAD_CHECK='Both';
      NO_IO_CHECK='Both';
      NO_ASSERT_CHECK='TRUE';
      NO_DIR_CHECK='TRUE';
      ALLOW_CONNECT='TRUE';
    'VSS104':
      PIN_NUMBER='(0,0,240)';
      PINUSE='POWER';
      NO_LOAD_CHECK='Both';
      NO_IO_CHECK='Both';
      NO_ASSERT_CHECK='TRUE';
      NO_DIR_CHECK='TRUE';
      ALLOW_CONNECT='TRUE';
    'VSS58':
      PIN_NUMBER='(0,0,132)';
      PINUSE='POWER';
      NO_LOAD_CHECK='Both';
      NO_IO_CHECK='Both';
      NO_ASSERT_CHECK='TRUE';
      NO_DIR_CHECK='TRUE';
      ALLOW_CONNECT='TRUE';
    'VSS60':
      PIN_NUMBER='(0,0,136)';
      PINUSE='POWER';
      NO_LOAD_CHECK='Both';
      NO_IO_CHECK='Both';
      NO_ASSERT_CHECK='TRUE';
      NO_DIR_CHECK='TRUE';
      ALLOW_CONNECT='TRUE';
    'VSS61':
      PIN_NUMBER='(0,0,139)';
      PINUSE='POWER';
      NO_LOAD_CHECK='Both';
      NO_IO_CHECK='Both';
      NO_ASSERT_CHECK='TRUE';
      NO_DIR_CHECK='TRUE';
      ALLOW_CONNECT='TRUE';
    'VSS62':
      PIN_NUMBER='(0,0,141)';
      PINUSE='POWER';
      NO_LOAD_CHECK='Both';
      NO_IO_CHECK='Both';
      NO_ASSERT_CHECK='TRUE';
      NO_DIR_CHECK='TRUE';
      ALLOW_CONNECT='TRUE';
    'G1':
      PIN_NUMBER='(0,0,G1)';
      PINUSE='POWER';
      NO_LOAD_CHECK='Both';
      NO_IO_CHECK='Both';
      NO_ASSERT_CHECK='TRUE';
      NO_DIR_CHECK='TRUE';
      ALLOW_CONNECT='TRUE';
    'G2':
      PIN_NUMBER='(0,0,G2)';
      PINUSE='POWER';
      NO_LOAD_CHECK='Both';
      NO_IO_CHECK='Both';
      NO_ASSERT_CHECK='TRUE';
      NO_DIR_CHECK='TRUE';
      ALLOW_CONNECT='TRUE';
    'G3':
      PIN_NUMBER='(0,0,G3)';
      PINUSE='POWER';
      NO_LOAD_CHECK='Both';
      NO_IO_CHECK='Both';
      NO_ASSERT_CHECK='TRUE';
      NO_DIR_CHECK='TRUE';
      ALLOW_CONNECT='TRUE';
  end_pin;
  body
    PART_NAME='SCONN288_ADR50017P130CC';
    BODY_NAME='SCONN288_ADR50017P130CC';
    PHYS_DES_PREFIX='J';
    CLASS='IO';
  end_body;
end_primitive;

END.
